(kicad_pcb
	(version 20260206)
	(generator "pcbnew")
	(generator_version "10.0")
	(general
		(thickness 1.6)
		(legacy_teardrops no)
	)
	(paper "A4")
	(title_block
		(title "01162023_DA0F0TEBIF0_F0T_Expander_BD_F_brd_V02_OCP.brd")
		(comment 1 "Grand Teton / footprints 2623-2629 of 9728")
	)
	(layers
		(0 "F.Cu" signal "TOP")
		(4 "In1.Cu" signal "GND")
		(6 "In2.Cu" signal "VCC")
		(8 "In3.Cu" signal "VCC1")
		(10 "In4.Cu" signal "GND1")
		(12 "In5.Cu" signal "IN1")
		(14 "In6.Cu" signal "GND2")
		(16 "In7.Cu" signal "IN2")
		(18 "In8.Cu" signal "GND3")
		(20 "In9.Cu" signal "IN3")
		(22 "In10.Cu" signal "GND4")
		(24 "In11.Cu" signal "IN4")
		(26 "In12.Cu" signal "GND5")
		(28 "In13.Cu" signal "IN5")
		(30 "In14.Cu" signal "GND6")
		(32 "In15.Cu" signal "IN6")
		(34 "In16.Cu" signal "GND7")
		(2 "B.Cu" signal "BOTTOM")
		(9 "F.Adhes" user "F.Adhesive")
		(11 "B.Adhes" user "B.Adhesive")
		(13 "F.Paste" user "Package Geometry/Pastemask Top")
		(15 "B.Paste" user "Package Geometry/Pastemask Bottom")
		(5 "F.SilkS" user "Ref Des/Silkscreen Top")
		(7 "B.SilkS" user "Ref Des/Silkscreen Bottom")
		(1 "F.Mask" user "Board Geometry/Soldermask Top")
		(3 "B.Mask" user "Board Geometry/Soldermask Bottom")
		(17 "Dwgs.User" user "User.Drawings")
		(19 "Cmts.User" user "User.Comments")
		(21 "Eco1.User" user "User.Eco1")
		(23 "Eco2.User" user "User.Eco2")
		(25 "Edge.Cuts" user "Board Geometry/Outline")
		(27 "Margin" user)
		(31 "F.CrtYd" user "Package Geometry/Place Bound Top")
		(29 "B.CrtYd" user "Package Geometry/Place Bound Bottom")
		(35 "F.Fab" user "Ref Des/Assembly Top")
		(33 "B.Fab" user "Ref Des/Assembly Bottom")
	)
	(footprint ""
		(layer "F.Cu")
		(at 162.275012 -48.753014 180)
		(property "Reference" "C309"
			(at 0 0 180)
			(layer "F.SilkS")
			(hide yes)
			(effects
				(font
					(size 1.27 1.27)
				)
			)
		)
		(property "Value" ""
			(at 0 0 180)
			(layer "F.Fab")
			(effects
				(font
					(size 1.27 1.27)
				)
			)
		)
		(duplicate_pad_numbers_are_jumpers no)
		(fp_line
			(start 0.7874 0.4064)
			(end -0.7874 0.4064)
			(stroke
				(width 0.1524)
				(type default)
			)
			(layer "F.SilkS")
		)
		(fp_line
			(start 0.7874 -0.4064)
			(end 0.7874 0.4064)
			(stroke
				(width 0.1524)
				(type default)
			)
			(layer "F.SilkS")
		)
		(fp_line
			(start -0.7874 0.4064)
			(end -0.7874 -0.4064)
			(stroke
				(width 0.1524)
				(type default)
			)
			(layer "F.SilkS")
		)
		(fp_line
			(start -0.7874 -0.4064)
			(end 0.7874 -0.4064)
			(stroke
				(width 0.1524)
				(type default)
			)
			(layer "F.SilkS")
		)
		(fp_line
			(start 0.67945 0.3048)
			(end 0.120396 0.3048)
			(stroke
				(width 0.1)
				(type default)
			)
			(layer "F.Fab")
		)
		(fp_line
			(start 0.67945 -0.3048)
			(end 0.67945 0.3048)
			(stroke
				(width 0.1)
				(type default)
			)
			(layer "F.Fab")
		)
		(fp_line
			(start 0.12065 -0.2794)
			(end 0.12065 -0.3048)
			(stroke
				(width 0.1)
				(type default)
			)
			(layer "F.Fab")
		)
		(fp_line
			(start 0.12065 -0.3048)
			(end 0.67945 -0.3048)
			(stroke
				(width 0.1)
				(type default)
			)
			(layer "F.Fab")
		)
		(fp_line
			(start 0.120396 0.3048)
			(end 0.120396 0.2794)
			(stroke
				(width 0.1)
				(type default)
			)
			(layer "F.Fab")
		)
		(fp_line
			(start 0.120396 0.2794)
			(end -0.12065 0.2794)
			(stroke
				(width 0.1)
				(type default)
			)
			(layer "F.Fab")
		)
		(fp_line
			(start -0.12065 0.3048)
			(end -0.67945 0.3048)
			(stroke
				(width 0.1)
				(type default)
			)
			(layer "F.Fab")
		)
		(fp_line
			(start -0.12065 0.2794)
			(end -0.12065 0.3048)
			(stroke
				(width 0.1)
				(type default)
			)
			(layer "F.Fab")
		)
		(fp_line
			(start -0.12065 -0.2794)
			(end 0.12065 -0.2794)
			(stroke
				(width 0.1)
				(type default)
			)
			(layer "F.Fab")
		)
		(fp_line
			(start -0.12065 -0.305054)
			(end -0.12065 -0.2794)
			(stroke
				(width 0.1)
				(type default)
			)
			(layer "F.Fab")
		)
		(fp_line
			(start -0.67945 0.3048)
			(end -0.67945 -0.305054)
			(stroke
				(width 0.1)
				(type default)
			)
			(layer "F.Fab")
		)
		(fp_line
			(start -0.67945 -0.305054)
			(end -0.12065 -0.305054)
			(stroke
				(width 0.1)
				(type default)
			)
			(layer "F.Fab")
		)
		(pad "1" smd circle
			(at -0.40005 0 180)
			(size 0 0)
			(layers "F.Cu" "F.Mask" "F.Paste")
			(net "P3V3_AUX")
		)
		(pad "2" smd circle
			(at 0.40005 0 180)
			(size 0 0)
			(layers "F.Cu" "F.Mask" "F.Paste")
			(net "GND")
		)
	)
	(footprint ""
		(layer "F.Cu")
		(at 239.813338 -138.360404 180)
		(property "Reference" "R4443"
			(at 0 0 180)
			(layer "F.SilkS")
			(hide yes)
			(effects
				(font
					(size 1.27 1.27)
				)
			)
		)
		(property "Value" ""
			(at 0 0 180)
			(layer "F.Fab")
			(effects
				(font
					(size 1.27 1.27)
				)
			)
		)
		(duplicate_pad_numbers_are_jumpers no)
		(fp_line
			(start 0.7874 0.4064)
			(end -0.7874 0.4064)
			(stroke
				(width 0.1524)
				(type default)
			)
			(layer "F.SilkS")
		)
		(fp_line
			(start 0.7874 -0.4064)
			(end 0.7874 0.4064)
			(stroke
				(width 0.1524)
				(type default)
			)
			(layer "F.SilkS")
		)
		(fp_line
			(start -0.7874 0.4064)
			(end -0.7874 -0.4064)
			(stroke
				(width 0.1524)
				(type default)
			)
			(layer "F.SilkS")
		)
		(fp_line
			(start -0.7874 -0.4064)
			(end 0.7874 -0.4064)
			(stroke
				(width 0.1524)
				(type default)
			)
			(layer "F.SilkS")
		)
		(fp_line
			(start 0.67945 0.3048)
			(end 0.120396 0.3048)
			(stroke
				(width 0.1)
				(type default)
			)
			(layer "F.Fab")
		)
		(fp_line
			(start 0.67945 -0.3048)
			(end 0.67945 0.3048)
			(stroke
				(width 0.1)
				(type default)
			)
			(layer "F.Fab")
		)
		(fp_line
			(start 0.12065 -0.2794)
			(end 0.12065 -0.3048)
			(stroke
				(width 0.1)
				(type default)
			)
			(layer "F.Fab")
		)
		(fp_line
			(start 0.12065 -0.3048)
			(end 0.67945 -0.3048)
			(stroke
				(width 0.1)
				(type default)
			)
			(layer "F.Fab")
		)
		(fp_line
			(start 0.120396 0.3048)
			(end 0.120396 0.2794)
			(stroke
				(width 0.1)
				(type default)
			)
			(layer "F.Fab")
		)
		(fp_line
			(start 0.120396 0.2794)
			(end -0.12065 0.2794)
			(stroke
				(width 0.1)
				(type default)
			)
			(layer "F.Fab")
		)
		(fp_line
			(start -0.12065 0.3048)
			(end -0.67945 0.3048)
			(stroke
				(width 0.1)
				(type default)
			)
			(layer "F.Fab")
		)
		(fp_line
			(start -0.12065 0.2794)
			(end -0.12065 0.3048)
			(stroke
				(width 0.1)
				(type default)
			)
			(layer "F.Fab")
		)
		(fp_line
			(start -0.12065 -0.2794)
			(end 0.12065 -0.2794)
			(stroke
				(width 0.1)
				(type default)
			)
			(layer "F.Fab")
		)
		(fp_line
			(start -0.12065 -0.305054)
			(end -0.12065 -0.2794)
			(stroke
				(width 0.1)
				(type default)
			)
			(layer "F.Fab")
		)
		(fp_line
			(start -0.67945 0.3048)
			(end -0.67945 -0.305054)
			(stroke
				(width 0.1)
				(type default)
			)
			(layer "F.Fab")
		)
		(fp_line
			(start -0.67945 -0.305054)
			(end -0.12065 -0.305054)
			(stroke
				(width 0.1)
				(type default)
			)
			(layer "F.Fab")
		)
		(pad "1" smd circle
			(at -0.40005 0 180)
			(size 0 0)
			(layers "F.Cu" "F.Mask" "F.Paste")
			(net "PWRGD_P12V_NIC4")
		)
		(pad "2" smd circle
			(at 0.40005 0 180)
			(size 0 0)
			(layers "F.Cu" "F.Mask" "F.Paste")
			(net "PWRGD_P12V_NIC4_R")
		)
	)
	(footprint ""
		(layer "F.Cu")
		(at 214.534496 -33.631886 180)
		(property "Reference" "C301"
			(at 0 0 180)
			(layer "F.SilkS")
			(hide yes)
			(effects
				(font
					(size 1.27 1.27)
				)
			)
		)
		(property "Value" ""
			(at 0 0 180)
			(layer "F.Fab")
			(effects
				(font
					(size 1.27 1.27)
				)
			)
		)
		(duplicate_pad_numbers_are_jumpers no)
		(fp_line
			(start 0.299974 0.150114)
			(end -0.299974 0.150114)
			(stroke
				(width 0.1)
				(type default)
			)
			(layer "F.Fab")
		)
		(fp_line
			(start 0.299974 -0.150114)
			(end 0.299974 0.150114)
			(stroke
				(width 0.1)
				(type default)
			)
			(layer "F.Fab")
		)
		(fp_line
			(start -0.299974 0.150114)
			(end -0.299974 -0.150114)
			(stroke
				(width 0.1)
				(type default)
			)
			(layer "F.Fab")
		)
		(fp_line
			(start -0.299974 -0.150114)
			(end 0.299974 -0.150114)
			(stroke
				(width 0.1)
				(type default)
			)
			(layer "F.Fab")
		)
		(pad "1" smd rect
			(at -0.2667 0 180)
			(size 0.3048 0.381)
			(layers "F.Cu" "F.Mask" "F.Paste")
			(net "P5E_PEX1_STN2_TX_DN<35>")
		)
		(pad "2" smd rect
			(at 0.2667 0 180)
			(size 0.3048 0.381)
			(layers "F.Cu" "F.Mask" "F.Paste")
			(net "P5E_PEX1_STN2_TX_C_DN<35>")
		)
	)
	(footprint ""
		(layer "F.Cu")
		(at 142.474442 -250.070874 -90)
		(property "Reference" "R1271"
			(at 0 0 270)
			(layer "F.SilkS")
			(hide yes)
			(effects
				(font
					(size 1.27 1.27)
				)
			)
		)
		(property "Value" ""
			(at 0 0 270)
			(layer "F.Fab")
			(effects
				(font
					(size 1.27 1.27)
				)
			)
		)
		(duplicate_pad_numbers_are_jumpers no)
		(fp_line
			(start -0.7874 0.4064)
			(end -0.7874 -0.4064)
			(stroke
				(width 0.1524)
				(type default)
			)
			(layer "F.SilkS")
		)
		(fp_line
			(start 0.7874 0.4064)
			(end -0.7874 0.4064)
			(stroke
				(width 0.1524)
				(type default)
			)
			(layer "F.SilkS")
		)
		(fp_line
			(start -0.7874 -0.4064)
			(end 0.7874 -0.4064)
			(stroke
				(width 0.1524)
				(type default)
			)
			(layer "F.SilkS")
		)
		(fp_line
			(start 0.7874 -0.4064)
			(end 0.7874 0.4064)
			(stroke
				(width 0.1524)
				(type default)
			)
			(layer "F.SilkS")
		)
		(fp_line
			(start -0.67945 0.3048)
			(end -0.67945 -0.305054)
			(stroke
				(width 0.1)
				(type default)
			)
			(layer "F.Fab")
		)
		(fp_line
			(start -0.12065 0.3048)
			(end -0.67945 0.3048)
			(stroke
				(width 0.1)
				(type default)
			)
			(layer "F.Fab")
		)
		(fp_line
			(start 0.120396 0.3048)
			(end 0.120396 0.2794)
			(stroke
				(width 0.1)
				(type default)
			)
			(layer "F.Fab")
		)
		(fp_line
			(start 0.67945 0.3048)
			(end 0.120396 0.3048)
			(stroke
				(width 0.1)
				(type default)
			)
			(layer "F.Fab")
		)
		(fp_line
			(start -0.12065 0.2794)
			(end -0.12065 0.3048)
			(stroke
				(width 0.1)
				(type default)
			)
			(layer "F.Fab")
		)
		(fp_line
			(start 0.120396 0.2794)
			(end -0.12065 0.2794)
			(stroke
				(width 0.1)
				(type default)
			)
			(layer "F.Fab")
		)
		(fp_line
			(start -0.12065 -0.2794)
			(end 0.12065 -0.2794)
			(stroke
				(width 0.1)
				(type default)
			)
			(layer "F.Fab")
		)
		(fp_line
			(start 0.12065 -0.2794)
			(end 0.12065 -0.3048)
			(stroke
				(width 0.1)
				(type default)
			)
			(layer "F.Fab")
		)
		(fp_line
			(start 0.12065 -0.3048)
			(end 0.67945 -0.3048)
			(stroke
				(width 0.1)
				(type default)
			)
			(layer "F.Fab")
		)
		(fp_line
			(start 0.67945 -0.3048)
			(end 0.67945 0.3048)
			(stroke
				(width 0.1)
				(type default)
			)
			(layer "F.Fab")
		)
		(fp_line
			(start -0.67945 -0.305054)
			(end -0.12065 -0.305054)
			(stroke
				(width 0.1)
				(type default)
			)
			(layer "F.Fab")
		)
		(fp_line
			(start -0.12065 -0.305054)
			(end -0.12065 -0.2794)
			(stroke
				(width 0.1)
				(type default)
			)
			(layer "F.Fab")
		)
		(pad "1" smd circle
			(at -0.40005 0 270)
			(size 0 0)
			(layers "F.Cu" "F.Mask" "F.Paste")
			(net "PEX1_MODE_SEL2")
		)
		(pad "2" smd circle
			(at 0.40005 0 270)
			(size 0 0)
			(layers "F.Cu" "F.Mask" "F.Paste")
			(net "P1V8_PEX")
		)
	)
	(footprint ""
		(layer "F.Cu")
		(at 292.743382 -356.244906 90)
		(property "Reference" "C2365"
			(at 0 0 90)
			(layer "F.SilkS")
			(hide yes)
			(effects
				(font
					(size 1.27 1.27)
				)
			)
		)
		(property "Value" ""
			(at 0 0 90)
			(layer "F.Fab")
			(effects
				(font
					(size 1.27 1.27)
				)
			)
		)
		(duplicate_pad_numbers_are_jumpers no)
		(fp_line
			(start 0.299974 -0.150114)
			(end 0.299974 0.150114)
			(stroke
				(width 0.1)
				(type default)
			)
			(layer "F.Fab")
		)
		(fp_line
			(start -0.299974 -0.150114)
			(end 0.299974 -0.150114)
			(stroke
				(width 0.1)
				(type default)
			)
			(layer "F.Fab")
		)
		(fp_line
			(start 0.299974 0.150114)
			(end -0.299974 0.150114)
			(stroke
				(width 0.1)
				(type default)
			)
			(layer "F.Fab")
		)
		(fp_line
			(start -0.299974 0.150114)
			(end -0.299974 -0.150114)
			(stroke
				(width 0.1)
				(type default)
			)
			(layer "F.Fab")
		)
		(pad "1" smd rect
			(at -0.2667 0 90)
			(size 0.3048 0.381)
			(layers "F.Cu" "F.Mask" "F.Paste")
			(net "P5E_PEX2_STN4_TX_DP<67>")
		)
		(pad "2" smd rect
			(at 0.2667 0 90)
			(size 0.3048 0.381)
			(layers "F.Cu" "F.Mask" "F.Paste")
			(net "P5E_PEX2_STN4_TX_C_DP<67>")
		)
	)
	(footprint ""
		(layer "F.Cu")
		(at 336.443574 -47.92091)
		(property "Reference" "R625"
			(at 0 0 0)
			(layer "F.SilkS")
			(hide yes)
			(effects
				(font
					(size 1.27 1.27)
				)
			)
		)
		(property "Value" ""
			(at 0 0 0)
			(layer "F.Fab")
			(effects
				(font
					(size 1.27 1.27)
				)
			)
		)
		(duplicate_pad_numbers_are_jumpers no)
		(fp_line
			(start -0.7874 -0.4064)
			(end 0.7874 -0.4064)
			(stroke
				(width 0.1524)
				(type default)
			)
			(layer "F.SilkS")
		)
		(fp_line
			(start -0.7874 0.4064)
			(end -0.7874 -0.4064)
			(stroke
				(width 0.1524)
				(type default)
			)
			(layer "F.SilkS")
		)
		(fp_line
			(start 0.7874 -0.4064)
			(end 0.7874 0.4064)
			(stroke
				(width 0.1524)
				(type default)
			)
			(layer "F.SilkS")
		)
		(fp_line
			(start 0.7874 0.4064)
			(end -0.7874 0.4064)
			(stroke
				(width 0.1524)
				(type default)
			)
			(layer "F.SilkS")
		)
		(fp_line
			(start -0.67945 -0.305054)
			(end -0.12065 -0.305054)
			(stroke
				(width 0.1)
				(type default)
			)
			(layer "F.Fab")
		)
		(fp_line
			(start -0.67945 0.3048)
			(end -0.67945 -0.305054)
			(stroke
				(width 0.1)
				(type default)
			)
			(layer "F.Fab")
		)
		(fp_line
			(start -0.12065 -0.305054)
			(end -0.12065 -0.2794)
			(stroke
				(width 0.1)
				(type default)
			)
			(layer "F.Fab")
		)
		(fp_line
			(start -0.12065 -0.2794)
			(end 0.12065 -0.2794)
			(stroke
				(width 0.1)
				(type default)
			)
			(layer "F.Fab")
		)
		(fp_line
			(start -0.12065 0.2794)
			(end -0.12065 0.3048)
			(stroke
				(width 0.1)
				(type default)
			)
			(layer "F.Fab")
		)
		(fp_line
			(start -0.12065 0.3048)
			(end -0.67945 0.3048)
			(stroke
				(width 0.1)
				(type default)
			)
			(layer "F.Fab")
		)
		(fp_line
			(start 0.120396 0.2794)
			(end -0.12065 0.2794)
			(stroke
				(width 0.1)
				(type default)
			)
			(layer "F.Fab")
		)
		(fp_line
			(start 0.120396 0.3048)
			(end 0.120396 0.2794)
			(stroke
				(width 0.1)
				(type default)
			)
			(layer "F.Fab")
		)
		(fp_line
			(start 0.12065 -0.3048)
			(end 0.67945 -0.3048)
			(stroke
				(width 0.1)
				(type default)
			)
			(layer "F.Fab")
		)
		(fp_line
			(start 0.12065 -0.2794)
			(end 0.12065 -0.3048)
			(stroke
				(width 0.1)
				(type default)
			)
			(layer "F.Fab")
		)
		(fp_line
			(start 0.67945 -0.3048)
			(end 0.67945 0.3048)
			(stroke
				(width 0.1)
				(type default)
			)
			(layer "F.Fab")
		)
		(fp_line
			(start 0.67945 0.3048)
			(end 0.120396 0.3048)
			(stroke
				(width 0.1)
				(type default)
			)
			(layer "F.Fab")
		)
		(pad "1" smd circle
			(at -0.40005 0)
			(size 0 0)
			(layers "F.Cu" "F.Mask" "F.Paste")
			(net "P3V3_AUX")
		)
		(pad "2" smd circle
			(at 0.40005 0)
			(size 0 0)
			(layers "F.Cu" "F.Mask" "F.Paste")
			(net "SSD_8_15_ADC_ALERT_N")
		)
	)
	(footprint ""
		(layer "F.Cu")
		(at 338.474304 -6.739636)
		(property "Reference" "R1712"
			(at 0 0 0)
			(layer "F.SilkS")
			(hide yes)
			(effects
				(font
					(size 1.27 1.27)
				)
			)
		)
		(property "Value" ""
			(at 0 0 0)
			(layer "F.Fab")
			(effects
				(font
					(size 1.27 1.27)
				)
			)
		)
		(duplicate_pad_numbers_are_jumpers no)
		(fp_line
			(start -0.7874 -0.4064)
			(end 0.7874 -0.4064)
			(stroke
				(width 0.1524)
				(type default)
			)
			(layer "F.SilkS")
		)
		(fp_line
			(start -0.7874 0.4064)
			(end -0.7874 -0.4064)
			(stroke
				(width 0.1524)
				(type default)
			)
			(layer "F.SilkS")
		)
		(fp_line
			(start 0.7874 -0.4064)
			(end 0.7874 0.4064)
			(stroke
				(width 0.1524)
				(type default)
			)
			(layer "F.SilkS")
		)
		(fp_line
			(start 0.7874 0.4064)
			(end -0.7874 0.4064)
			(stroke
				(width 0.1524)
				(type default)
			)
			(layer "F.SilkS")
		)
		(fp_line
			(start -0.67945 -0.305054)
			(end -0.12065 -0.305054)
			(stroke
				(width 0.1)
				(type default)
			)
			(layer "F.Fab")
		)
		(fp_line
			(start -0.67945 0.3048)
			(end -0.67945 -0.305054)
			(stroke
				(width 0.1)
				(type default)
			)
			(layer "F.Fab")
		)
		(fp_line
			(start -0.12065 -0.305054)
			(end -0.12065 -0.2794)
			(stroke
				(width 0.1)
				(type default)
			)
			(layer "F.Fab")
		)
		(fp_line
			(start -0.12065 -0.2794)
			(end 0.12065 -0.2794)
			(stroke
				(width 0.1)
				(type default)
			)
			(layer "F.Fab")
		)
		(fp_line
			(start -0.12065 0.2794)
			(end -0.12065 0.3048)
			(stroke
				(width 0.1)
				(type default)
			)
			(layer "F.Fab")
		)
		(fp_line
			(start -0.12065 0.3048)
			(end -0.67945 0.3048)
			(stroke
				(width 0.1)
				(type default)
			)
			(layer "F.Fab")
		)
		(fp_line
			(start 0.120396 0.2794)
			(end -0.12065 0.2794)
			(stroke
				(width 0.1)
				(type default)
			)
			(layer "F.Fab")
		)
		(fp_line
			(start 0.120396 0.3048)
			(end 0.120396 0.2794)
			(stroke
				(width 0.1)
				(type default)
			)
			(layer "F.Fab")
		)
		(fp_line
			(start 0.12065 -0.3048)
			(end 0.67945 -0.3048)
			(stroke
				(width 0.1)
				(type default)
			)
			(layer "F.Fab")
		)
		(fp_line
			(start 0.12065 -0.2794)
			(end 0.12065 -0.3048)
			(stroke
				(width 0.1)
				(type default)
			)
			(layer "F.Fab")
		)
		(fp_line
			(start 0.67945 -0.3048)
			(end 0.67945 0.3048)
			(stroke
				(width 0.1)
				(type default)
			)
			(layer "F.Fab")
		)
		(fp_line
			(start 0.67945 0.3048)
			(end 0.120396 0.3048)
			(stroke
				(width 0.1)
				(type default)
			)
			(layer "F.Fab")
		)
		(pad "1" smd circle
			(at -0.40005 0)
			(size 0 0)
			(layers "F.Cu" "F.Mask" "F.Paste")
			(net "SMB_BIC_I2C9_MUX1_SSD11_R_SDA")
		)
		(pad "2" smd circle
			(at 0.40005 0)
			(size 0 0)
			(layers "F.Cu" "F.Mask" "F.Paste")
			(net "SMB_ISO_SSD11_SDA")
		)
	)
)
